(kicad_pcb
	(version 20260206)
	(generator "pcbnew")
	(generator_version "10.0")
	(general
		(thickness 1.6)
		(legacy_teardrops no)
	)
	(paper "A4")
	(title_block
		(title "baseboard — 13948-1b.1110WZS1818.brd")
		(comment 1 "Honey Badger (Wiwynn) / footprints 1633-1638 of 2523")
	)
	(layers
		(0 "F.Cu" signal "TOP")
		(4 "In1.Cu" signal "L2GND")
		(6 "In2.Cu" signal "L3")
		(8 "In3.Cu" signal "L4VCC")
		(10 "In4.Cu" signal "L5VCC")
		(12 "In5.Cu" signal "L6")
		(14 "In6.Cu" signal "L7GND")
		(2 "B.Cu" signal "BOTTOM")
		(9 "F.Adhes" user "F.Adhesive")
		(11 "B.Adhes" user "B.Adhesive")
		(13 "F.Paste" user "Package Geometry/Pastemask Top")
		(15 "B.Paste" user "Package Geometry/Pastemask Bottom")
		(5 "F.SilkS" user "Ref Des/Silkscreen Top")
		(7 "B.SilkS" user "Ref Des/Silkscreen Bottom")
		(1 "F.Mask" user "Board Geometry/Soldermask Top")
		(3 "B.Mask" user "Board Geometry/Soldermask Bottom")
		(17 "Dwgs.User" user "User.Drawings")
		(19 "Cmts.User" user "User.Comments")
		(21 "Eco1.User" user "User.Eco1")
		(23 "Eco2.User" user "User.Eco2")
		(25 "Edge.Cuts" user "Board Geometry/Outline")
		(27 "Margin" user)
		(31 "F.CrtYd" user "Package Geometry/Place Bound Top")
		(29 "B.CrtYd" user "Package Geometry/Place Bound Bottom")
		(35 "F.Fab" user "Ref Des/Assembly Top")
		(33 "B.Fab" user "Ref Des/Assembly Bottom")
	)
	(footprint ""
		(layer "F.Cu")
		(at 54.864 -224.917)
		(property "Reference" "R2098"
			(at 0 0 0)
			(layer "F.SilkS")
			(hide yes)
			(effects
				(font
					(size 1.27 1.27)
				)
			)
		)
		(property "Value" "10R2F-L-GP"
			(at 0.064008 -3.993896 0)
			(unlocked yes)
			(layer "F.Fab")
			(hide yes)
			(effects
				(font
					(size 1.016 1.016)
					(thickness 0.1524)
				)
			)
		)
		(property "Device Type" "R402H14"
			(at 0.064008 -5.517896 0)
			(unlocked yes)
			(layer "F.Fab")
			(hide yes)
			(effects
				(font
					(size 1.016 1.016)
					(thickness 0.1524)
				)
			)
		)
		(duplicate_pad_numbers_are_jumpers no)
		(fp_line
			(start -0.508 -0.9398)
			(end -0.508 0.9398)
			(stroke
				(width 0.1524)
				(type default)
			)
			(layer "F.SilkS")
		)
		(fp_line
			(start 0.508 -0.9398)
			(end -0.508 -0.9398)
			(stroke
				(width 0.1524)
				(type default)
			)
			(layer "F.SilkS")
		)
		(fp_rect
			(start -0.508 0.9398)
			(end 0.508 -0.9398)
			(stroke
				(width 0)
				(type default)
			)
			(fill no)
			(layer "F.CrtYd")
		)
		(fp_rect
			(start -0.508 0.9398)
			(end 0.508 -0.9398)
			(stroke
				(width 0)
				(type default)
			)
			(fill no)
			(layer "F.Fab")
		)
		(pad "1" smd custom
			(at 0 -0.4445)
			(size 0.1397 0.1397)
			(layers "F.Cu" "F.Mask" "F.Paste")
			(net "P12V_PCIE")
			(options
				(clearance outline)
				(anchor circle)
			)
			(primitives
				(gr_poly
					(pts
						(arc
							(start -0.1778 -0.2794)
							(mid -0.249642 -0.249642)
							(end -0.2794 -0.1778)
						)
						(arc
							(start -0.2794 0.1778)
							(mid -0.249642 0.249642)
							(end -0.1778 0.2794)
						)
						(arc
							(start 0.1778 0.2794)
							(mid 0.249642 0.249642)
							(end 0.2794 0.1778)
						)
						(arc
							(start 0.2794 -0.1778)
							(mid 0.249642 -0.249642)
							(end 0.1778 -0.2794)
						)
					)
					(width 0)
					(fill yes)
				)
			)
		)
		(pad "2" smd custom
			(at 0 0.4445)
			(size 0.1397 0.1397)
			(layers "F.Cu" "F.Mask" "F.Paste")
			(net "MB0_VCC")
			(options
				(clearance outline)
				(anchor circle)
			)
			(primitives
				(gr_poly
					(pts
						(arc
							(start -0.1778 -0.2794)
							(mid -0.249642 -0.249642)
							(end -0.2794 -0.1778)
						)
						(arc
							(start -0.2794 0.1778)
							(mid -0.249642 0.249642)
							(end -0.1778 0.2794)
						)
						(arc
							(start 0.1778 0.2794)
							(mid 0.249642 0.249642)
							(end 0.2794 0.1778)
						)
						(arc
							(start 0.2794 -0.1778)
							(mid 0.249642 -0.249642)
							(end 0.1778 -0.2794)
						)
					)
					(width 0)
					(fill yes)
				)
			)
		)
	)
	(footprint ""
		(layer "F.Cu")
		(at 81.915 -24.892 90)
		(property "Reference" "PR194"
			(at 0 0 90)
			(layer "F.SilkS")
			(hide yes)
			(effects
				(font
					(size 1.27 1.27)
				)
			)
		)
		(property "Value" "287R2F-GP"
			(at 0.064008 -3.993896 90)
			(unlocked yes)
			(layer "F.Fab")
			(hide yes)
			(effects
				(font
					(size 1.016 1.016)
					(thickness 0.1524)
				)
			)
		)
		(property "Device Type" "R402H16"
			(at 0.064008 -5.517896 90)
			(unlocked yes)
			(layer "F.Fab")
			(hide yes)
			(effects
				(font
					(size 1.016 1.016)
					(thickness 0.1524)
				)
			)
		)
		(duplicate_pad_numbers_are_jumpers no)
		(fp_line
			(start 0.508 -0.9398)
			(end -0.508 -0.9398)
			(stroke
				(width 0.1524)
				(type default)
			)
			(layer "F.SilkS")
		)
		(fp_line
			(start -0.508 -0.9398)
			(end -0.508 0.9398)
			(stroke
				(width 0.1524)
				(type default)
			)
			(layer "F.SilkS")
		)
		(fp_rect
			(start -0.508 0.9398)
			(end 0.508 -0.9398)
			(stroke
				(width 0)
				(type default)
			)
			(fill no)
			(layer "F.CrtYd")
		)
		(fp_rect
			(start -0.508 0.9398)
			(end 0.508 -0.9398)
			(stroke
				(width 0)
				(type default)
			)
			(fill no)
			(layer "F.Fab")
		)
		(pad "1" smd custom
			(at 0 -0.4445 90)
			(size 0.1397 0.1397)
			(layers "F.Cu" "F.Mask" "F.Paste")
			(net "VT235_VDES_RR")
			(options
				(clearance outline)
				(anchor circle)
			)
			(primitives
				(gr_poly
					(pts
						(arc
							(start -0.1778 -0.2794)
							(mid -0.249642 -0.249642)
							(end -0.2794 -0.1778)
						)
						(arc
							(start -0.2794 0.1778)
							(mid -0.249642 0.249642)
							(end -0.1778 0.2794)
						)
						(arc
							(start 0.1778 0.2794)
							(mid 0.249642 0.249642)
							(end 0.2794 0.1778)
						)
						(arc
							(start 0.2794 -0.1778)
							(mid 0.249642 -0.249642)
							(end 0.1778 -0.2794)
						)
					)
					(width 0)
					(fill yes)
				)
			)
		)
		(pad "2" smd custom
			(at 0 0.4445 90)
			(size 0.1397 0.1397)
			(layers "F.Cu" "F.Mask" "F.Paste")
			(net "VT235_VDES_RCC")
			(options
				(clearance outline)
				(anchor circle)
			)
			(primitives
				(gr_poly
					(pts
						(arc
							(start -0.1778 -0.2794)
							(mid -0.249642 -0.249642)
							(end -0.2794 -0.1778)
						)
						(arc
							(start -0.2794 0.1778)
							(mid -0.249642 0.249642)
							(end -0.1778 0.2794)
						)
						(arc
							(start 0.1778 0.2794)
							(mid 0.249642 0.249642)
							(end 0.2794 0.1778)
						)
						(arc
							(start 0.2794 -0.1778)
							(mid 0.249642 -0.249642)
							(end 0.1778 -0.2794)
						)
					)
					(width 0)
					(fill yes)
				)
			)
		)
	)
	(footprint ""
		(layer "F.Cu")
		(at 215.15197 -69.088)
		(property "Reference" "R18"
			(at 0 0 0)
			(layer "F.SilkS")
			(hide yes)
			(effects
				(font
					(size 1.27 1.27)
				)
			)
		)
		(property "Value" "100R2F-L1-GP-U"
			(at 0.064008 -3.993896 0)
			(unlocked yes)
			(layer "F.Fab")
			(hide yes)
			(effects
				(font
					(size 1.016 1.016)
					(thickness 0.1524)
				)
			)
		)
		(property "Device Type" "R402H14"
			(at 0.064008 -5.517896 0)
			(unlocked yes)
			(layer "F.Fab")
			(hide yes)
			(effects
				(font
					(size 1.016 1.016)
					(thickness 0.1524)
				)
			)
		)
		(duplicate_pad_numbers_are_jumpers no)
		(fp_line
			(start -0.508 -0.9398)
			(end -0.508 0.9398)
			(stroke
				(width 0.1524)
				(type default)
			)
			(layer "F.SilkS")
		)
		(fp_line
			(start 0.508 -0.9398)
			(end -0.508 -0.9398)
			(stroke
				(width 0.1524)
				(type default)
			)
			(layer "F.SilkS")
		)
		(fp_rect
			(start -0.508 0.9398)
			(end 0.508 -0.9398)
			(stroke
				(width 0)
				(type default)
			)
			(fill no)
			(layer "F.CrtYd")
		)
		(fp_rect
			(start -0.508 0.9398)
			(end 0.508 -0.9398)
			(stroke
				(width 0)
				(type default)
			)
			(fill no)
			(layer "F.Fab")
		)
		(pad "1" smd custom
			(at 0 -0.4445)
			(size 0.1397 0.1397)
			(layers "F.Cu" "F.Mask" "F.Paste")
			(net "SVR_ID3")
			(options
				(clearance outline)
				(anchor circle)
			)
			(primitives
				(gr_poly
					(pts
						(arc
							(start -0.1778 -0.2794)
							(mid -0.249642 -0.249642)
							(end -0.2794 -0.1778)
						)
						(arc
							(start -0.2794 0.1778)
							(mid -0.249642 0.249642)
							(end -0.1778 0.2794)
						)
						(arc
							(start 0.1778 0.2794)
							(mid 0.249642 0.249642)
							(end 0.2794 0.1778)
						)
						(arc
							(start 0.2794 -0.1778)
							(mid 0.249642 -0.249642)
							(end 0.1778 -0.2794)
						)
					)
					(width 0)
					(fill yes)
				)
			)
		)
		(pad "2" smd custom
			(at 0 0.4445)
			(size 0.1397 0.1397)
			(layers "F.Cu" "F.Mask" "F.Paste")
			(net "GND")
			(options
				(clearance outline)
				(anchor circle)
			)
			(primitives
				(gr_poly
					(pts
						(arc
							(start -0.1778 -0.2794)
							(mid -0.249642 -0.249642)
							(end -0.2794 -0.1778)
						)
						(arc
							(start -0.2794 0.1778)
							(mid -0.249642 0.249642)
							(end -0.1778 0.2794)
						)
						(arc
							(start 0.1778 0.2794)
							(mid 0.249642 0.249642)
							(end 0.2794 0.1778)
						)
						(arc
							(start 0.2794 -0.1778)
							(mid 0.249642 -0.249642)
							(end 0.1778 -0.2794)
						)
					)
					(width 0)
					(fill yes)
				)
			)
		)
	)
	(footprint ""
		(layer "F.Cu")
		(at 340.868 -20.193 180)
		(property "Reference" "R1582"
			(at 0 0 180)
			(layer "F.SilkS")
			(hide yes)
			(effects
				(font
					(size 1.27 1.27)
				)
			)
		)
		(property "Value" "33R2F-3-GP"
			(at 0.064008 -3.993896 180)
			(unlocked yes)
			(layer "F.Fab")
			(hide yes)
			(effects
				(font
					(size 1.016 1.016)
					(thickness 0.1524)
				)
			)
		)
		(property "Device Type" "R402H16"
			(at 0.064008 -5.517896 180)
			(unlocked yes)
			(layer "F.Fab")
			(hide yes)
			(effects
				(font
					(size 1.016 1.016)
					(thickness 0.1524)
				)
			)
		)
		(duplicate_pad_numbers_are_jumpers no)
		(fp_line
			(start 0.508 -0.9398)
			(end -0.508 -0.9398)
			(stroke
				(width 0.1524)
				(type default)
			)
			(layer "F.SilkS")
		)
		(fp_line
			(start -0.508 -0.9398)
			(end -0.508 0.9398)
			(stroke
				(width 0.1524)
				(type default)
			)
			(layer "F.SilkS")
		)
		(fp_rect
			(start -0.508 0.9398)
			(end 0.508 -0.9398)
			(stroke
				(width 0)
				(type default)
			)
			(fill no)
			(layer "F.CrtYd")
		)
		(fp_rect
			(start -0.508 0.9398)
			(end 0.508 -0.9398)
			(stroke
				(width 0)
				(type default)
			)
			(fill no)
			(layer "F.Fab")
		)
		(pad "1" smd custom
			(at 0 -0.4445 180)
			(size 0.1397 0.1397)
			(layers "F.Cu" "F.Mask" "F.Paste")
			(net "CPU_EXP_RST")
			(options
				(clearance outline)
				(anchor circle)
			)
			(primitives
				(gr_poly
					(pts
						(arc
							(start -0.1778 -0.2794)
							(mid -0.249642 -0.249642)
							(end -0.2794 -0.1778)
						)
						(arc
							(start -0.2794 0.1778)
							(mid -0.249642 0.249642)
							(end -0.1778 0.2794)
						)
						(arc
							(start 0.1778 0.2794)
							(mid 0.249642 0.249642)
							(end 0.2794 0.1778)
						)
						(arc
							(start 0.2794 -0.1778)
							(mid 0.249642 -0.249642)
							(end 0.1778 -0.2794)
						)
					)
					(width 0)
					(fill yes)
				)
			)
		)
		(pad "2" smd custom
			(at 0 0.4445 180)
			(size 0.1397 0.1397)
			(layers "F.Cu" "F.Mask" "F.Paste")
			(net "FP_RESET_RC_N")
			(options
				(clearance outline)
				(anchor circle)
			)
			(primitives
				(gr_poly
					(pts
						(arc
							(start -0.1778 -0.2794)
							(mid -0.249642 -0.249642)
							(end -0.2794 -0.1778)
						)
						(arc
							(start -0.2794 0.1778)
							(mid -0.249642 0.249642)
							(end -0.1778 0.2794)
						)
						(arc
							(start 0.1778 0.2794)
							(mid 0.249642 0.249642)
							(end 0.2794 0.1778)
						)
						(arc
							(start 0.2794 -0.1778)
							(mid 0.249642 -0.249642)
							(end 0.1778 -0.2794)
						)
					)
					(width 0)
					(fill yes)
				)
			)
		)
	)
	(footprint ""
		(layer "F.Cu")
		(at 179.324 -16.129 -90)
		(property "Reference" "R204"
			(at 0 0 270)
			(layer "F.SilkS")
			(hide yes)
			(effects
				(font
					(size 1.27 1.27)
				)
			)
		)
		(property "Value" "0R2J-2-GP"
			(at 0.064008 -3.993896 270)
			(unlocked yes)
			(layer "F.Fab")
			(hide yes)
			(effects
				(font
					(size 1.016 1.016)
					(thickness 0.1524)
				)
			)
		)
		(property "Device Type" "R402H16"
			(at 0.064008 -5.517896 270)
			(unlocked yes)
			(layer "F.Fab")
			(hide yes)
			(effects
				(font
					(size 1.016 1.016)
					(thickness 0.1524)
				)
			)
		)
		(duplicate_pad_numbers_are_jumpers no)
		(fp_line
			(start -0.508 -0.9398)
			(end -0.508 0.9398)
			(stroke
				(width 0.1524)
				(type default)
			)
			(layer "F.SilkS")
		)
		(fp_line
			(start 0.508 -0.9398)
			(end -0.508 -0.9398)
			(stroke
				(width 0.1524)
				(type default)
			)
			(layer "F.SilkS")
		)
		(fp_rect
			(start -0.508 0.9398)
			(end 0.508 -0.9398)
			(stroke
				(width 0)
				(type default)
			)
			(fill no)
			(layer "F.CrtYd")
		)
		(fp_rect
			(start -0.508 0.9398)
			(end 0.508 -0.9398)
			(stroke
				(width 0)
				(type default)
			)
			(fill no)
			(layer "F.Fab")
		)
		(pad "1" smd custom
			(at 0 -0.4445 270)
			(size 0.1397 0.1397)
			(layers "F.Cu" "F.Mask" "F.Paste")
			(net "TEMP_SENSOR_C")
			(options
				(clearance outline)
				(anchor circle)
			)
			(primitives
				(gr_poly
					(pts
						(arc
							(start -0.1778 -0.2794)
							(mid -0.249642 -0.249642)
							(end -0.2794 -0.1778)
						)
						(arc
							(start -0.2794 0.1778)
							(mid -0.249642 0.249642)
							(end -0.1778 0.2794)
						)
						(arc
							(start 0.1778 0.2794)
							(mid 0.249642 0.249642)
							(end 0.2794 0.1778)
						)
						(arc
							(start 0.2794 -0.1778)
							(mid 0.249642 -0.249642)
							(end 0.1778 -0.2794)
						)
					)
					(width 0)
					(fill yes)
				)
			)
		)
		(pad "2" smd custom
			(at 0 0.4445 270)
			(size 0.1397 0.1397)
			(layers "F.Cu" "F.Mask" "F.Paste")
			(net "TEMP_SENSOR_DXN_BJT")
			(options
				(clearance outline)
				(anchor circle)
			)
			(primitives
				(gr_poly
					(pts
						(arc
							(start -0.1778 -0.2794)
							(mid -0.249642 -0.249642)
							(end -0.2794 -0.1778)
						)
						(arc
							(start -0.2794 0.1778)
							(mid -0.249642 0.249642)
							(end -0.1778 0.2794)
						)
						(arc
							(start 0.1778 0.2794)
							(mid 0.249642 0.249642)
							(end 0.2794 0.1778)
						)
						(arc
							(start 0.2794 -0.1778)
							(mid 0.249642 -0.249642)
							(end 0.1778 -0.2794)
						)
					)
					(width 0)
					(fill yes)
				)
			)
		)
	)
	(footprint ""
		(layer "F.Cu")
		(at 267.335 -66.04 180)
		(property "Reference" "Q76"
			(at 0 0 180)
			(layer "F.SilkS")
			(hide yes)
			(effects
				(font
					(size 1.27 1.27)
				)
			)
		)
		(property "Value" "PSMN0R9-25YLC-GP"
			(at -4.2799 -0.4572 180)
			(unlocked yes)
			(layer "F.Fab")
			(hide yes)
			(effects
				(font
					(size 1.016 1.016)
					(thickness 0.1524)
				)
			)
		)
		(property "Device Type" "LFPAK-5PH48-U"
			(at -4.2799 -1.9812 180)
			(unlocked yes)
			(layer "F.Fab")
			(hide yes)
			(effects
				(font
					(size 1.016 1.016)
					(thickness 0.1524)
				)
			)
		)
		(duplicate_pad_numbers_are_jumpers no)
		(fp_line
			(start 2.7559 1.0668)
			(end 2.7559 -6.5532)
			(stroke
				(width 0.1524)
				(type default)
			)
			(layer "F.SilkS")
		)
		(fp_line
			(start 2.7559 -6.5532)
			(end -2.7559 -6.5532)
			(stroke
				(width 0.1524)
				(type default)
			)
			(layer "F.SilkS")
		)
		(fp_line
			(start -1.7272 1.1684)
			(end -2.1082 1.1684)
			(stroke
				(width 0.3302)
				(type default)
			)
			(layer "F.SilkS")
		)
		(fp_line
			(start -2.7559 1.0668)
			(end 2.7559 1.0668)
			(stroke
				(width 0.1524)
				(type default)
			)
			(layer "F.SilkS")
		)
		(fp_line
			(start -2.7559 -6.5532)
			(end -2.7559 1.0668)
			(stroke
				(width 0.1524)
				(type default)
			)
			(layer "F.SilkS")
		)
		(fp_poly
			(pts
				(xy -2.3368 1.5748) (xy -1.905 1.143) (xy -1.4732 1.5748)
			)
			(stroke
				(width 0)
				(type default)
			)
			(fill yes)
			(layer "F.SilkS")
		)
		(fp_poly
			(pts
				(xy 0.3302 -1.09601) (xy 2.5019 -1.09601) (xy 2.5019 -3.36931) (xy 0.3302 -3.36931)
			)
			(stroke
				(width 0)
				(type default)
			)
			(fill yes)
			(layer "F.Paste")
		)
		(fp_poly
			(pts
				(xy 0.3302 -4.02971) (xy 2.5019 -4.02971) (xy 2.5019 -6.30301) (xy 0.3302 -6.30301)
			)
			(stroke
				(width 0)
				(type default)
			)
			(fill yes)
			(layer "F.Paste")
		)
		(fp_poly
			(pts
				(xy -2.5019 -1.09601) (xy -0.3302 -1.09601) (xy -0.3302 -3.36931) (xy -2.5019 -3.36931)
			)
			(stroke
				(width 0)
				(type default)
			)
			(fill yes)
			(layer "F.Paste")
		)
		(fp_poly
			(pts
				(xy -2.5019 -4.02971) (xy -0.3302 -4.02971) (xy -0.3302 -6.30301) (xy -2.5019 -6.30301)
			)
			(stroke
				(width 0)
				(type default)
			)
			(fill yes)
			(layer "F.Paste")
		)
		(fp_rect
			(start -2.4511 0.3048)
			(end 2.4511 -5.6896)
			(stroke
				(width 0)
				(type default)
			)
			(fill no)
			(layer "F.CrtYd")
		)
		(fp_poly
			(pts
				(xy -3.0099 1.3208) (xy -3.0099 -6.8072) (xy 3.0099 -6.8072) (xy 3.0099 -1.016) (xy 2.4511 -1.016)
				(xy 2.4511 -5.6896) (xy -2.4511 -5.6896) (xy -2.4511 0.3048) (xy 2.4511 0.3048) (xy 2.4511 -1.0033)
				(xy 3.0099 -1.0033) (xy 3.0099 1.3208)
			)
			(stroke
				(width 0)
				(type default)
			)
			(fill no)
			(layer "F.CrtYd")
		)
		(fp_rect
			(start -3.0099 1.3208)
			(end 3.0099 -6.8072)
			(stroke
				(width 0)
				(type default)
			)
			(fill no)
			(layer "F.Fab")
		)
		(pad "1" smd rect
			(at -1.905 0 180)
			(size 0.762 1.6256)
			(layers "F.Cu" "F.Mask" "F.Paste")
			(net "P12V_MSB")
		)
		(pad "2" smd rect
			(at -0.635 0 180)
			(size 0.762 1.6256)
			(layers "F.Cu" "F.Mask" "F.Paste")
			(net "P12V_MSB")
		)
		(pad "3" smd rect
			(at 0.635 0 180)
			(size 0.762 1.6256)
			(layers "F.Cu" "F.Mask" "F.Paste")
			(net "P12V_MSB")
		)
		(pad "4" smd rect
			(at 1.905 0 180)
			(size 0.762 1.6256)
			(layers "F.Cu" "F.Mask" "F.Paste")
			(net "VR_HSC_GATE_R_MSB")
		)
		(pad "5" smd rect
			(at 0 -3.69951 180)
			(size 5.0038 5.207)
			(layers "F.Cu" "F.Mask" "F.Paste")
			(net "VSENSE_HSC_MSB")
		)
	)
)
